# BASEBOARD_FAB2 (Tioga Pass) — schematic netlist excerpt (pin names and nets, part order shuffled) for the footprints in the layout excerpt that follows; sources: Cadence DE-HDL packaged netlist, KiCad conversion of Wiwynn_Tioga_Pass_MB.brd

C5G97  CAP_A  22.0UF 4V 20% X6S  pkg 0603V  page 243 : A = PVDDQ_KLM ; B = GND
C5G78  CAP  47UF 4V 20% X6S  pkg 0805  page 242 : A = PVDDQ_DEF ; B = GND
R9L7  RES  1.00K 1% CHIP  pkg 0402  page 100 : A = PVDDQ_KLM ; B = M_L_VREF

(kicad_pcb
	(version 20260206)
	(generator "pcbnew")
	(generator_version "10.0")
	(general
		(thickness 1.6)
		(legacy_teardrops no)
	)
	(paper "A4")
	(title_block
		(title "Wiwynn_Tioga_Pass_MB.brd")
		(comment 1 "Tioga Pass / footprints 3959-3961 of 4770")
	)
	(layers
		(0 "F.Cu" signal "TOP")
		(4 "In1.Cu" signal "L2GND")
		(6 "In2.Cu" signal "L3")
		(8 "In3.Cu" signal "L4GND")
		(10 "In4.Cu" signal "L5")
		(12 "In5.Cu" signal "L6GND")
		(14 "In6.Cu" signal "L7VCC")
		(16 "In7.Cu" signal "L8VCC")
		(18 "In8.Cu" signal "L9GND")
		(20 "In9.Cu" signal "L10")
		(22 "In10.Cu" signal "L11GND")
		(24 "In11.Cu" signal "L12")
		(26 "In12.Cu" signal "L13GND")
		(2 "B.Cu" signal "BOTTOM")
		(9 "F.Adhes" user "F.Adhesive")
		(11 "B.Adhes" user "B.Adhesive")
		(13 "F.Paste" user "Package Geometry/Pastemask Top")
		(15 "B.Paste" user "Package Geometry/Pastemask Bottom")
		(5 "F.SilkS" user "Ref Des/Silkscreen Top")
		(7 "B.SilkS" user "Ref Des/Silkscreen Bottom")
		(1 "F.Mask" user "Board Geometry/Soldermask Top")
		(3 "B.Mask" user "Board Geometry/Soldermask Bottom")
		(17 "Dwgs.User" user "User.Drawings")
		(19 "Cmts.User" user "User.Comments")
		(21 "Eco1.User" user "User.Eco1")
		(23 "Eco2.User" user "User.Eco2")
		(25 "Edge.Cuts" user "Board Geometry/Outline")
		(27 "Margin" user)
		(31 "F.CrtYd" user "Package Geometry/Place Bound Top")
		(29 "B.CrtYd" user "Package Geometry/Place Bound Bottom")
		(35 "F.Fab" user "Ref Des/Assembly Top")
		(33 "B.Fab" user "Ref Des/Assembly Bottom")
	)
	(footprint ""
		(layer "B.Cu")
		(at 259.5626 -140.081 90)
		(property "Reference" "C5G78"
			(at -1.64973 0.78994 180)
			(unlocked yes)
			(layer "B.SilkS")
			(effects
				(font
					(size 0.7874 0.5842)
					(thickness 0.1524)
				)
				(justify mirror)
			)
		)
		(property "Value" ""
			(at 0 0 90)
			(layer "B.Fab")
			(effects
				(font
					(size 1.27 1.27)
				)
				(justify mirror)
			)
		)
		(duplicate_pad_numbers_are_jumpers no)
		(fp_rect
			(start -0.7239 -0.2159)
			(end 0.7239 1.9939)
			(stroke
				(width 0)
				(type default)
			)
			(fill no)
			(layer "B.CrtYd")
		)
		(fp_line
			(start 0.7239 -0.2159)
			(end 0.7239 1.9939)
			(stroke
				(width 0.1)
				(type default)
			)
			(layer "B.Fab")
		)
		(fp_line
			(start -0.7239 -0.2159)
			(end 0.7239 -0.2159)
			(stroke
				(width 0.1)
				(type default)
			)
			(layer "B.Fab")
		)
		(fp_line
			(start 0.7239 1.9939)
			(end -0.7239 1.9939)
			(stroke
				(width 0.1)
				(type default)
			)
			(layer "B.Fab")
		)
		(fp_line
			(start -0.7239 1.9939)
			(end -0.7239 -0.2159)
			(stroke
				(width 0.1)
				(type default)
			)
			(layer "B.Fab")
		)
		(pad "1" smd rect
			(at 0 0 270)
			(size 1.27 1.016)
			(layers "B.Cu" "B.Mask" "B.Paste")
			(net "PVDDQ_DEF")
		)
		(pad "2" smd rect
			(at 0 1.778 270)
			(size 1.27 1.016)
			(layers "B.Cu" "B.Mask" "B.Paste")
			(net "GND")
		)
		(zone
			(layer "B.Cu")
			(hatch none 0.5)
			(connect_pads
				(clearance 0)
			)
			(min_thickness 0.25)
			(keepout
				(tracks not_allowed)
				(vias allowed)
				(pads allowed)
				(copperpour not_allowed)
				(footprints allowed)
			)
			(placement
				(enabled no)
				(sheetname "")
			)
			(fill
				(thermal_gap 0.5)
				(thermal_bridge_width 0.5)
				(island_removal_mode 0)
			)
			(polygon
				(pts
					(xy 260.0706 -139.446) (xy 260.8326 -139.446) (xy 260.8326 -140.716) (xy 260.0706 -140.716)
				)
			)
		)
	)
	(footprint ""
		(layer "B.Cu")
		(at 28.547568 -144.4752 180)
		(property "Reference" "R9L7"
			(at 0 0 0)
			(layer "B.SilkS")
			(hide yes)
			(effects
				(font
					(size 1.27 1.27)
				)
				(justify mirror)
			)
		)
		(property "Value" ""
			(at 0 0 0)
			(layer "B.Fab")
			(effects
				(font
					(size 1.27 1.27)
				)
				(justify mirror)
			)
		)
		(duplicate_pad_numbers_are_jumpers no)
		(fp_poly
			(pts
				(xy 0.2794 -0.1016) (xy -0.2794 -0.1016) (xy -0.2794 0.9906) (xy 0.2794 0.9906)
			)
			(stroke
				(width 0)
				(type default)
			)
			(fill no)
			(layer "B.CrtYd")
		)
		(fp_line
			(start 0.2794 0.9906)
			(end -0.2794 0.9906)
			(stroke
				(width 0.1)
				(type default)
			)
			(layer "B.Fab")
		)
		(fp_line
			(start 0.2794 -0.1016)
			(end 0.2794 0.9906)
			(stroke
				(width 0.1)
				(type default)
			)
			(layer "B.Fab")
		)
		(fp_line
			(start -0.2794 0.9906)
			(end -0.2794 -0.1016)
			(stroke
				(width 0.1)
				(type default)
			)
			(layer "B.Fab")
		)
		(fp_line
			(start -0.2794 -0.1016)
			(end 0.2794 -0.1016)
			(stroke
				(width 0.1)
				(type default)
			)
			(layer "B.Fab")
		)
		(pad "1" smd rect
			(at 0 0)
			(size 0.508 0.508)
			(layers "B.Cu" "B.Mask" "B.Paste")
			(net "PVDDQ_KLM")
		)
		(pad "2" smd rect
			(at 0 0.889)
			(size 0.508 0.508)
			(layers "B.Cu" "B.Mask" "B.Paste")
			(net "M_L_VREF")
		)
		(zone
			(layer "B.Cu")
			(hatch none 0.5)
			(connect_pads
				(clearance 0)
			)
			(min_thickness 0.25)
			(keepout
				(tracks not_allowed)
				(vias allowed)
				(pads allowed)
				(copperpour not_allowed)
				(footprints allowed)
			)
			(placement
				(enabled no)
				(sheetname "")
			)
			(fill
				(thermal_gap 0.5)
				(thermal_bridge_width 0.5)
				(island_removal_mode 0)
			)
			(polygon
				(pts
					(xy 28.293568 -145.1102) (xy 28.801568 -145.1102) (xy 28.801568 -144.7292) (xy 28.293568 -144.7292)
				)
			)
		)
		(zone
			(layer "B.Cu")
			(hatch none 0.5)
			(connect_pads
				(clearance 0)
			)
			(min_thickness 0.25)
			(keepout
				(tracks allowed)
				(vias not_allowed)
				(pads allowed)
				(copperpour not_allowed)
				(footprints allowed)
			)
			(placement
				(enabled no)
				(sheetname "")
			)
			(fill
				(thermal_gap 0.5)
				(thermal_bridge_width 0.5)
				(island_removal_mode 0)
			)
			(polygon
				(pts
					(xy 28.293568 -144.7292) (xy 28.801568 -144.7292) (xy 28.801568 -145.1102) (xy 28.293568 -145.1102)
				)
			)
		)
	)
	(footprint ""
		(layer "B.Cu")
		(at 92.85986 -149.77872 -90)
		(property "Reference" "C5G97"
			(at -1.14681 0.76708 0)
			(unlocked yes)
			(layer "B.SilkS")
			(effects
				(font
					(size 0.7874 0.5842)
					(thickness 0.1524)
				)
				(justify mirror)
			)
		)
		(property "Value" ""
			(at 0 0 90)
			(layer "B.Fab")
			(effects
				(font
					(size 1.27 1.27)
				)
				(justify mirror)
			)
		)
		(duplicate_pad_numbers_are_jumpers no)
		(fp_rect
			(start -0.4953 -0.2032)
			(end 0.4953 1.6002)
			(stroke
				(width 0)
				(type default)
			)
			(fill no)
			(layer "B.CrtYd")
		)
		(fp_line
			(start -0.4953 1.6002)
			(end 0.4953 1.6002)
			(stroke
				(width 0.1)
				(type default)
			)
			(layer "B.Fab")
		)
		(fp_line
			(start 0.4953 1.6002)
			(end 0.4953 -0.2032)
			(stroke
				(width 0.1)
				(type default)
			)
			(layer "B.Fab")
		)
		(fp_line
			(start -0.4953 -0.2032)
			(end -0.4953 1.6002)
			(stroke
				(width 0.1)
				(type default)
			)
			(layer "B.Fab")
		)
		(fp_line
			(start 0.4953 -0.2032)
			(end -0.4953 -0.2032)
			(stroke
				(width 0.1)
				(type default)
			)
			(layer "B.Fab")
		)
		(pad "1" smd rect
			(at 0 0 90)
			(size 0.762 0.889)
			(layers "B.Cu" "B.Mask" "B.Paste")
			(net "PVDDQ_KLM")
		)
		(pad "2" smd rect
			(at 0 1.397 90)
			(size 0.762 0.889)
			(layers "B.Cu" "B.Mask" "B.Paste")
			(net "GND")
		)
		(zone
			(layer "B.Cu")
			(hatch none 0.5)
			(connect_pads
				(clearance 0)
			)
			(min_thickness 0.25)
			(keepout
				(tracks not_allowed)
				(vias allowed)
				(pads allowed)
				(copperpour not_allowed)
				(footprints allowed)
			)
			(placement
				(enabled no)
				(sheetname "")
			)
			(fill
				(thermal_gap 0.5)
				(thermal_bridge_width 0.5)
				(island_removal_mode 0)
			)
			(polygon
				(pts
					(xy 92.41536 -150.15972) (xy 91.90736 -150.15972) (xy 91.90736 -149.39772) (xy 92.41536 -149.39772)
				)
			)
		)
	)
)
